# T6G (Grand Teton) — schematic netlist excerpt (pin names and nets, part order shuffled) for the footprints in the layout excerpt that follows; sources: Cadence DE-HDL packaged netlist, KiCad conversion of 04192023_DAF0TMB3IC0_F0TG_MB_C_brd_V02_OCP.brd

R70  Q_RES  0 5% CHIP  pkg 0402LF  page 80 : A = SMB_CPU0_4_XLTR_R_SCL ; B = SMB_CPU0_4_XLTR_SCL

(kicad_pcb
	(version 20260206)
	(generator "pcbnew")
	(generator_version "10.0")
	(general
		(thickness 1.6)
		(legacy_teardrops no)
	)
	(paper "A4")
	(title_block
		(title "04192023_DAF0TMB3IC0_F0TG_MB_C_brd_V02_OCP.brd")
		(comment 1 "Grand Teton / footprints 2108-2108 of 8354")
	)
	(layers
		(0 "F.Cu" signal "TOP")
		(4 "In1.Cu" signal "GND")
		(6 "In2.Cu" signal "IN1")
		(8 "In3.Cu" signal "GND1")
		(10 "In4.Cu" signal "IN2")
		(12 "In5.Cu" signal "GND2")
		(14 "In6.Cu" signal "IN3")
		(16 "In7.Cu" signal "GND3")
		(18 "In8.Cu" signal "VCC")
		(20 "In9.Cu" signal "VCC1")
		(22 "In10.Cu" signal "GND4")
		(24 "In11.Cu" signal "IN4")
		(26 "In12.Cu" signal "GND5")
		(28 "In13.Cu" signal "IN5")
		(30 "In14.Cu" signal "GND6")
		(32 "In15.Cu" signal "IN6")
		(34 "In16.Cu" signal "GND7")
		(2 "B.Cu" signal "BOTTOM")
		(9 "F.Adhes" user "F.Adhesive")
		(11 "B.Adhes" user "B.Adhesive")
		(13 "F.Paste" user "Package Geometry/Pastemask Top")
		(15 "B.Paste" user "Package Geometry/Pastemask Bottom")
		(5 "F.SilkS" user "Ref Des/Silkscreen Top")
		(7 "B.SilkS" user "Ref Des/Silkscreen Bottom")
		(1 "F.Mask" user "Board Geometry/Soldermask Top")
		(3 "B.Mask" user "Board Geometry/Soldermask Bottom")
		(17 "Dwgs.User" user "User.Drawings")
		(19 "Cmts.User" user "User.Comments")
		(21 "Eco1.User" user "User.Eco1")
		(23 "Eco2.User" user "User.Eco2")
		(25 "Edge.Cuts" user "Board Geometry/Outline")
		(27 "Margin" user)
		(31 "F.CrtYd" user "Package Geometry/Place Bound Top")
		(29 "B.CrtYd" user "Package Geometry/Place Bound Bottom")
		(35 "F.Fab" user "Ref Des/Assembly Top")
		(33 "B.Fab" user "Ref Des/Assembly Bottom")
	)
	(footprint ""
		(layer "F.Cu")
		(at 179.846224 -147.086574 90)
		(property "Reference" "R70"
			(at 0 0 90)
			(layer "F.SilkS")
			(hide yes)
			(effects
				(font
					(size 1.27 1.27)
				)
			)
		)
		(property "Value" ""
			(at 0 0 90)
			(layer "F.Fab")
			(effects
				(font
					(size 1.27 1.27)
				)
			)
		)
		(duplicate_pad_numbers_are_jumpers no)
		(fp_line
			(start 0.7874 -0.4064)
			(end 0.7874 0.4064)
			(stroke
				(width 0.1524)
				(type default)
			)
			(layer "F.SilkS")
		)
		(fp_line
			(start -0.7874 -0.4064)
			(end 0.7874 -0.4064)
			(stroke
				(width 0.1524)
				(type default)
			)
			(layer "F.SilkS")
		)
		(fp_line
			(start 0.7874 0.4064)
			(end -0.7874 0.4064)
			(stroke
				(width 0.1524)
				(type default)
			)
			(layer "F.SilkS")
		)
		(fp_line
			(start -0.7874 0.4064)
			(end -0.7874 -0.4064)
			(stroke
				(width 0.1524)
				(type default)
			)
			(layer "F.SilkS")
		)
		(fp_line
			(start -0.12065 -0.305054)
			(end -0.12065 -0.2794)
			(stroke
				(width 0.1)
				(type default)
			)
			(layer "F.Fab")
		)
		(fp_line
			(start -0.67945 -0.305054)
			(end -0.12065 -0.305054)
			(stroke
				(width 0.1)
				(type default)
			)
			(layer "F.Fab")
		)
		(fp_line
			(start 0.67945 -0.3048)
			(end 0.67945 0.3048)
			(stroke
				(width 0.1)
				(type default)
			)
			(layer "F.Fab")
		)
		(fp_line
			(start 0.12065 -0.3048)
			(end 0.67945 -0.3048)
			(stroke
				(width 0.1)
				(type default)
			)
			(layer "F.Fab")
		)
		(fp_line
			(start 0.12065 -0.2794)
			(end 0.12065 -0.3048)
			(stroke
				(width 0.1)
				(type default)
			)
			(layer "F.Fab")
		)
		(fp_line
			(start -0.12065 -0.2794)
			(end 0.12065 -0.2794)
			(stroke
				(width 0.1)
				(type default)
			)
			(layer "F.Fab")
		)
		(fp_line
			(start 0.120396 0.2794)
			(end -0.12065 0.2794)
			(stroke
				(width 0.1)
				(type default)
			)
			(layer "F.Fab")
		)
		(fp_line
			(start -0.12065 0.2794)
			(end -0.12065 0.3048)
			(stroke
				(width 0.1)
				(type default)
			)
			(layer "F.Fab")
		)
		(fp_line
			(start 0.67945 0.3048)
			(end 0.120396 0.3048)
			(stroke
				(width 0.1)
				(type default)
			)
			(layer "F.Fab")
		)
		(fp_line
			(start 0.120396 0.3048)
			(end 0.120396 0.2794)
			(stroke
				(width 0.1)
				(type default)
			)
			(layer "F.Fab")
		)
		(fp_line
			(start -0.12065 0.3048)
			(end -0.67945 0.3048)
			(stroke
				(width 0.1)
				(type default)
			)
			(layer "F.Fab")
		)
		(fp_line
			(start -0.67945 0.3048)
			(end -0.67945 -0.305054)
			(stroke
				(width 0.1)
				(type default)
			)
			(layer "F.Fab")
		)
		(pad "1" smd circle
			(at -0.40005 0 90)
			(size 0 0)
			(layers "F.Cu" "F.Mask" "F.Paste")
			(net "SMB_CPU0_4_XLTR_R_SCL")
		)
		(pad "2" smd circle
			(at 0.40005 0 90)
			(size 0 0)
			(layers "F.Cu" "F.Mask" "F.Paste")
			(net "SMB_CPU0_4_XLTR_SCL")
		)
	)
)
